(kicad_pcb
	(version 20221018)
	(generator pcbnew)
	(general
    (thickness 1.7403)
  )
	(paper "A4")
	(title_block
    (title "Data Center RDIMM DDR4 Tester")
    (date "2024-09-30")
    (rev "1.2.4")
		(comment 9 "footprints 115-118 of 690")
	)
	(layers
    (0 "F.Cu" signal)
    (1 "In1.Cu" power)
    (2 "In2.Cu" signal)
    (3 "In3.Cu" power)
    (4 "In4.Cu" power)
    (5 "In5.Cu" signal)
    (6 "In6.Cu" power)
    (7 "In7.Cu" signal)
    (8 "In8.Cu" power)
    (9 "In9.Cu" signal)
    (10 "In10.Cu" power)
    (31 "B.Cu" signal)
    (32 "B.Adhes" user "B.Adhesive")
    (33 "F.Adhes" user "F.Adhesive")
    (34 "B.Paste" user)
    (35 "F.Paste" user)
    (36 "B.SilkS" user "B.Silkscreen")
    (37 "F.SilkS" user "F.Silkscreen")
    (38 "B.Mask" user)
    (39 "F.Mask" user)
    (40 "Dwgs.User" user "User.Drawings")
    (41 "Cmts.User" user "User.Comments")
    (42 "Eco1.User" user "User.Eco1")
    (43 "Eco2.User" user "User.Eco2")
    (44 "Edge.Cuts" user)
    (45 "Margin" user)
    (46 "B.CrtYd" user "B.Courtyard")
    (47 "F.CrtYd" user "F.Courtyard")
    (48 "B.Fab" user)
    (49 "F.Fab" user)
  )
	(footprint "data-center-rdimm-ddr4-tester-footprints:QFN-48-1EP_7x7x0.9mm_P0.5mm_EP3.5x3.5mm" (layer "F.Cu")
    (at 158.436328 96.047157 90)
    (property "Author" "Antmicro")
    (property "License" "Apache-2.0")
    (property "MPN" "KSZ9031RNXCA")
    (property "Manufacturer" "Microchip Technology")
    (property "Sheetfile" "ethernet.kicad_sch")
    (property "Sheetname" "Ethernet")
    (property "ki_description" "Ethernet Controller, 1000 Mbps, IEEE 802.3, 1.14 V, 3.465 V, QFN, 48 Pins")
    (property "ki_keywords" "SMT, TRANSCEIVER, IC, ETHERNET, PHY")
    (attr smd)
    (fp_text reference "U6" (at -4.282843 -4.3 90) (layer "F.SilkS")
        (effects (font (size 0.7 0.7) (thickness 0.15)) (justify left bottom))
    )
    (fp_text value "KSZ9031RNXCA" (at 0 5.1 90) (layer "F.Fab") hide
        (effects (font (size 0.7 0.7) (thickness 0.15)) (justify left bottom))
    )
    (fp_text user "${REFERENCE}" (at -4.202 7.2 90) (layer "F.Fab") hide
        (effects (font (size 0.7 0.7) (thickness 0.15)) (justify left bottom))
    )
    (fp_text user "Author: Antmicro" (at -4.202 8.4 90) (layer "F.Fab") hide
        (effects (font (size 0.7 0.7) (thickness 0.15)) (justify left bottom))
    )
    (fp_text user "License: Apache-2.0" (at -4.202 9.598 90) (layer "F.Fab") hide
        (effects (font (size 0.7 0.7) (thickness 0.15)) (justify left bottom))
    )
    (fp_line (start -3.65 -3.3) (end -3.65 -3.65)
      (stroke (width 0.15) (type solid)) (layer "F.SilkS"))
    (fp_line (start -3.65 3.648) (end -3.65 3.249)
      (stroke (width 0.15) (type solid)) (layer "F.SilkS"))
    (fp_line (start -3.3 -3.65) (end -3.65 -3.65)
      (stroke (width 0.15) (type solid)) (layer "F.SilkS"))
    (fp_line (start -3.25 3.648) (end -3.65 3.648)
      (stroke (width 0.15) (type solid)) (layer "F.SilkS"))
    (fp_line (start 3.249 -3.65) (end 3.648 -3.65)
      (stroke (width 0.15) (type solid)) (layer "F.SilkS"))
    (fp_line (start 3.249 3.648) (end 3.648 3.648)
      (stroke (width 0.15) (type solid)) (layer "F.SilkS"))
    (fp_line (start 3.648 -3.65) (end 3.648 -3.25)
      (stroke (width 0.15) (type solid)) (layer "F.SilkS"))
    (fp_line (start 3.648 3.648) (end 3.648 3.249)
      (stroke (width 0.15) (type solid)) (layer "F.SilkS"))
    (fp_circle (center -3.7 -3.05) (end -3.65 -3.05)
      (stroke (width 0.15) (type solid)) (fill solid) (layer "F.SilkS"))
    (fp_rect (start -4.15 -4.15) (end 4.15 4.15)
      (stroke (width 0.05) (type solid)) (fill none) (layer "F.CrtYd"))
    (fp_line (start -3.5 -2.5) (end -3.5 3.499)
      (stroke (width 0.15) (type solid)) (layer "F.Fab"))
    (fp_line (start -3.5 3.499) (end 3.499 3.499)
      (stroke (width 0.15) (type solid)) (layer "F.Fab"))
    (fp_line (start -2.5 -3.5) (end -3.5 -2.5)
      (stroke (width 0.15) (type solid)) (layer "F.Fab"))
    (fp_line (start 3.499 -3.5) (end -2.5 -3.5)
      (stroke (width 0.15) (type solid)) (layer "F.Fab"))
    (fp_line (start 3.499 3.499) (end 3.499 -3.5)
      (stroke (width 0.15) (type solid)) (layer "F.Fab"))
    (pad "1" smd oval (at -3.5 -2.75 180) (size 0.3 0.9) (layers "F.Cu" "F.Paste" "F.Mask")
      (net 179 "/Ethernet/AVDDH") (pinfunction "AVDDH") (pintype "power_in"))
    (pad "2" smd oval (at -3.5 -2.25 180) (size 0.3 0.9) (layers "F.Cu" "F.Paste" "F.Mask")
      (net 170 "/Ethernet/ETH1_P") (pinfunction "TXRXP_A") (pintype "bidirectional"))
    (pad "3" smd oval (at -3.5 -1.75 180) (size 0.3 0.9) (layers "F.Cu" "F.Paste" "F.Mask")
      (net 173 "/Ethernet/ETH1_N") (pinfunction "TXRXM_A") (pintype "bidirectional"))
    (pad "4" smd oval (at -3.5 -1.25 180) (size 0.3 0.9) (layers "F.Cu" "F.Paste" "F.Mask")
      (net 177 "/Ethernet/AVDDL") (pinfunction "AVDDL") (pintype "power_in"))
    (pad "5" smd oval (at -3.5 -0.75 180) (size 0.3 0.9) (layers "F.Cu" "F.Paste" "F.Mask")
      (net 169 "/Ethernet/ETH2_P") (pinfunction "TXRXP_B") (pintype "bidirectional"))
    (pad "6" smd oval (at -3.5 -0.25 180) (size 0.3 0.9) (layers "F.Cu" "F.Paste" "F.Mask")
      (net 172 "/Ethernet/ETH2_N") (pinfunction "TXRXM_B") (pintype "bidirectional"))
    (pad "7" smd oval (at -3.5 0.248 180) (size 0.3 0.9) (layers "F.Cu" "F.Paste" "F.Mask")
      (net 168 "/Ethernet/ETH3_P") (pinfunction "TXRXP_C") (pintype "bidirectional"))
    (pad "8" smd oval (at -3.5 0.748 180) (size 0.3 0.9) (layers "F.Cu" "F.Paste" "F.Mask")
      (net 174 "/Ethernet/ETH3_N") (pinfunction "TXRXM_C") (pintype "bidirectional"))
    (pad "9" smd oval (at -3.5 1.249 180) (size 0.3 0.9) (layers "F.Cu" "F.Paste" "F.Mask")
      (net 177 "/Ethernet/AVDDL") (pinfunction "AVDDL") (pintype "passive"))
    (pad "10" smd oval (at -3.5 1.749 180) (size 0.3 0.9) (layers "F.Cu" "F.Paste" "F.Mask")
      (net 171 "/Ethernet/ETH4_P") (pinfunction "TXRXP_D") (pintype "bidirectional"))
    (pad "11" smd oval (at -3.5 2.249 180) (size 0.3 0.9) (layers "F.Cu" "F.Paste" "F.Mask")
      (net 175 "/Ethernet/ETH4_N") (pinfunction "TXRXM_D") (pintype "bidirectional"))
    (pad "12" smd oval (at -3.5 2.749 180) (size 0.3 0.9) (layers "F.Cu" "F.Paste" "F.Mask")
      (net 179 "/Ethernet/AVDDH") (pinfunction "AVDDH") (pintype "passive"))
    (pad "13" smd oval (at -2.75 3.499 90) (size 0.3 0.9) (layers "F.Cu" "F.Paste" "F.Mask")
      (net 670 "unconnected-(U6-NC-Pad13)") (pinfunction "NC") (pintype "no_connect"))
    (pad "14" smd oval (at -2.25 3.499 90) (size 0.3 0.9) (layers "F.Cu" "F.Paste" "F.Mask")
      (net 306 "1V2_SYS") (pinfunction "DVDDL") (pintype "power_in"))
    (pad "15" smd oval (at -1.75 3.499 90) (size 0.3 0.9) (layers "F.Cu" "F.Paste" "F.Mask")
      (net 17 "LED_SPD") (pinfunction "LED2/PHYAD1") (pintype "bidirectional"))
    (pad "16" smd oval (at -1.25 3.499 90) (size 0.3 0.9) (layers "F.Cu" "F.Paste" "F.Mask")
      (net 143 "3V3_SYS") (pinfunction "DVDDH") (pintype "power_in"))
    (pad "17" smd oval (at -0.75 3.499 90) (size 0.3 0.9) (layers "F.Cu" "F.Paste" "F.Mask")
      (net 16 "LED_LINK") (pinfunction "LED1/PHAD0/PME_N1") (pintype "bidirectional"))
    (pad "18" smd oval (at -0.25 3.499 90) (size 0.3 0.9) (layers "F.Cu" "F.Paste" "F.Mask")
      (net 306 "1V2_SYS") (pinfunction "DVDDL") (pintype "passive"))
    (pad "19" smd oval (at 0.248 3.499 90) (size 0.3 0.9) (layers "F.Cu" "F.Paste" "F.Mask")
      (net 36 "ETH_TXD0") (pinfunction "TXD0") (pintype "input"))
    (pad "20" smd oval (at 0.748 3.499 90) (size 0.3 0.9) (layers "F.Cu" "F.Paste" "F.Mask")
      (net 31 "ETH_TXD1") (pinfunction "TXD1") (pintype "input"))
    (pad "21" smd oval (at 1.249 3.499 90) (size 0.3 0.9) (layers "F.Cu" "F.Paste" "F.Mask")
      (net 32 "ETH_TXD2") (pinfunction "TXD2") (pintype "input"))
    (pad "22" smd oval (at 1.749 3.499 90) (size 0.3 0.9) (layers "F.Cu" "F.Paste" "F.Mask")
      (net 33 "ETH_TXD3") (pinfunction "TXD3") (pintype "input"))
    (pad "23" smd oval (at 2.249 3.499 90) (size 0.3 0.9) (layers "F.Cu" "F.Paste" "F.Mask")
      (net 306 "1V2_SYS") (pinfunction "DVDDL") (pintype "passive"))
    (pad "24" smd oval (at 2.749 3.499 90) (size 0.3 0.9) (layers "F.Cu" "F.Paste" "F.Mask")
      (net 34 "ETH_TX_CLK") (pinfunction "GTX_CLK") (pintype "input"))
    (pad "25" smd oval (at 3.499 2.749 180) (size 0.3 0.9) (layers "F.Cu" "F.Paste" "F.Mask")
      (net 35 "ETH_TX_EN") (pinfunction "TX_EN") (pintype "input"))
    (pad "26" smd oval (at 3.499 2.249 180) (size 0.3 0.9) (layers "F.Cu" "F.Paste" "F.Mask")
      (net 306 "1V2_SYS") (pinfunction "DVDDL") (pintype "passive"))
    (pad "27" smd oval (at 3.499 1.749 180) (size 0.3 0.9) (layers "F.Cu" "F.Paste" "F.Mask")
      (net 37 "ETH_RXD3") (pinfunction "RXD3/MODE3") (pintype "input"))
    (pad "28" smd oval (at 3.499 1.249 180) (size 0.3 0.9) (layers "F.Cu" "F.Paste" "F.Mask")
      (net 41 "ETH_RXD2") (pinfunction "RXD2/MODE2") (pintype "input"))
    (pad "29" smd oval (at 3.499 0.748 180) (size 0.3 0.9) (layers "F.Cu" "F.Paste" "F.Mask")
      (net 9 "GND") (pinfunction "VSS") (pintype "power_in"))
    (pad "30" smd oval (at 3.499 0.248 180) (size 0.3 0.9) (layers "F.Cu" "F.Paste" "F.Mask")
      (net 306 "1V2_SYS") (pinfunction "DVDDL") (pintype "passive"))
    (pad "31" smd oval (at 3.499 -0.25 180) (size 0.3 0.9) (layers "F.Cu" "F.Paste" "F.Mask")
      (net 27 "ETH_RXD1") (pinfunction "RXD1/MODE1") (pintype "input"))
    (pad "32" smd oval (at 3.499 -0.75 180) (size 0.3 0.9) (layers "F.Cu" "F.Paste" "F.Mask")
      (net 26 "ETH_RXD0") (pinfunction "RXD0/MODE0") (pintype "input"))
    (pad "33" smd oval (at 3.499 -1.25 180) (size 0.3 0.9) (layers "F.Cu" "F.Paste" "F.Mask")
      (net 38 "ETH_RX_DV") (pinfunction "RX_DV/CLK125_EN") (pintype "input"))
    (pad "34" smd oval (at 3.499 -1.75 180) (size 0.3 0.9) (layers "F.Cu" "F.Paste" "F.Mask")
      (net 143 "3V3_SYS") (pinfunction "DVDDH") (pintype "passive"))
    (pad "35" smd oval (at 3.499 -2.25 180) (size 0.3 0.9) (layers "F.Cu" "F.Paste" "F.Mask")
      (net 40 "ETH_RX_CLK") (pinfunction "RX_CLK/PHYAD2") (pintype "input"))
    (pad "36" smd oval (at 3.499 -2.75 180) (size 0.3 0.9) (layers "F.Cu" "F.Paste" "F.Mask")
      (net 39 "ETH_MDC") (pinfunction "MDC") (pintype "input"))
    (pad "37" smd oval (at 2.749 -3.5 90) (size 0.3 0.9) (layers "F.Cu" "F.Paste" "F.Mask")
      (net 29 "ETH_MDIO") (pinfunction "MDIO") (pintype "input"))
    (pad "38" smd oval (at 2.249 -3.5 90) (size 0.3 0.9) (layers "F.Cu" "F.Paste" "F.Mask")
      (net 183 "ETH_INT_N") (pinfunction "~{INT/PME}") (pintype "input"))
    (pad "39" smd oval (at 1.749 -3.5 90) (size 0.3 0.9) (layers "F.Cu" "F.Paste" "F.Mask")
      (net 306 "1V2_SYS") (pinfunction "DVDDL") (pintype "passive"))
    (pad "40" smd oval (at 1.249 -3.5 90) (size 0.3 0.9) (layers "F.Cu" "F.Paste" "F.Mask")
      (net 143 "3V3_SYS") (pinfunction "DVDDH") (pintype "passive"))
    (pad "41" smd oval (at 0.748 -3.5 90) (size 0.3 0.9) (layers "F.Cu" "F.Paste" "F.Mask")
      (net 30 "ETH_REF_CLK") (pinfunction "CLK125_NDO/LED_MODE") (pintype "input"))
    (pad "42" smd oval (at 0.248 -3.5 90) (size 0.3 0.9) (layers "F.Cu" "F.Paste" "F.Mask")
      (net 28 "ETH_RSTN") (pinfunction "~{RESET}") (pintype "input"))
    (pad "43" smd oval (at -0.25 -3.5 90) (size 0.3 0.9) (layers "F.Cu" "F.Paste" "F.Mask")
      (net 671 "unconnected-(U6-LDO_O-Pad43)") (pinfunction "LDO_O") (pintype "input+no_connect"))
    (pad "44" smd oval (at -0.75 -3.5 90) (size 0.3 0.9) (layers "F.Cu" "F.Paste" "F.Mask")
      (net 178 "/Ethernet/AVDDL_PLL") (pinfunction "AVDDL_PLL") (pintype "power_in"))
    (pad "45" smd oval (at -1.25 -3.5 90) (size 0.3 0.9) (layers "F.Cu" "F.Paste" "F.Mask")
      (net 5 "Net-(U6-XO)") (pinfunction "XO") (pintype "input"))
    (pad "46" smd oval (at -1.75 -3.5 90) (size 0.3 0.9) (layers "F.Cu" "F.Paste" "F.Mask")
      (net 6 "Net-(U6-XI)") (pinfunction "XI") (pintype "input"))
    (pad "47" smd oval (at -2.25 -3.5 90) (size 0.3 0.9) (layers "F.Cu" "F.Paste" "F.Mask")
      (net 672 "unconnected-(U6-NC-Pad47)") (pinfunction "NC") (pintype "no_connect"))
    (pad "48" smd oval (at -2.75 -3.5 90) (size 0.3 0.9) (layers "F.Cu" "F.Paste" "F.Mask")
      (net 652 "Net-(U6-ISET)") (pinfunction "ISET") (pintype "output"))
    (pad "49" smd rect (at 0 0 90) (size 3.5 3.5) (layers "F.Cu" "F.Paste" "F.Mask")
      (net 9 "GND") (pinfunction "PAD_GND") (pintype "power_in"))
  )
	(footprint "data-center-rdimm-ddr4-tester-footprints:R_0402_1005Metric" (layer "F.Cu")
    (at 208.63 113.135 -90)
    (descr "Resistor SMD 0402")
    (tags "resistor SMD 0402")
    (property "Author" "Antmicro")
    (property "Current" "1A")
    (property "License" "Apache-2.0")
    (property "MPN" "ERJ2GE0R00X")
    (property "Manufacturer" "Panasonic")
    (property "Sheetfile" "interfaces.kicad_sch")
    (property "Sheetname" "Interfaces")
    (property "Tolerance" "")
    (property "Val" "0R")
    (property "ki_description" "0R resistor in 0402 package with unspecified tolerance")
    (attr smd)
    (fp_text reference "R139" (at -3.515 -0.34 -90) (layer "F.SilkS")
        (effects (font (size 0.7 0.7) (thickness 0.15)) (justify left bottom))
    )
    (fp_text value "R_0R_0402" (at 0 1.4 -90) (layer "F.Fab") hide
        (effects (font (size 0.7 0.7) (thickness 0.15)) (justify left bottom))
    )
    (fp_text user "${REFERENCE}" (at -0.95 3.168 -90) (layer "F.Fab") hide
        (effects (font (size 0.7 0.7) (thickness 0.15)) (justify left bottom))
    )
    (fp_text user "License: Apache-2.0" (at -0.95 5.169 -90) (layer "F.Fab") hide
        (effects (font (size 0.7 0.7) (thickness 0.15)) (justify left bottom))
    )
    (fp_text user "Author: Antmicro" (at -0.95 4.169 -90) (layer "F.Fab") hide
        (effects (font (size 0.7 0.7) (thickness 0.15)) (justify left bottom))
    )
    (fp_rect (start -0.93 -0.47) (end 0.93 0.47)
      (stroke (width 0.05) (type solid)) (fill none) (layer "F.CrtYd"))
    (fp_rect (start -0.5 -0.25) (end 0.5 0.25)
      (stroke (width 0.15) (type solid)) (fill none) (layer "F.Fab"))
    (pad "1" smd roundrect (at -0.485 0 270) (size 0.59 0.64) (layers "F.Cu" "F.Paste" "F.Mask") (roundrect_rratio 0.25)
      (net 56 "TMDS_CLK_N") (pintype "passive"))
    (pad "2" smd roundrect (at 0.485 0 270) (size 0.59 0.64) (layers "F.Cu" "F.Paste" "F.Mask") (roundrect_rratio 0.25)
      (net 43 "C_TMDS_CLK_N") (pintype "passive"))
  )
	(footprint "data-center-rdimm-ddr4-tester-footprints:R_0402_1005Metric" (layer "F.Cu")
    (at 209.655 113.135 -90)
    (descr "Resistor SMD 0402")
    (tags "resistor SMD 0402")
    (property "Author" "Antmicro")
    (property "Current" "1A")
    (property "License" "Apache-2.0")
    (property "MPN" "ERJ2GE0R00X")
    (property "Manufacturer" "Panasonic")
    (property "Sheetfile" "interfaces.kicad_sch")
    (property "Sheetname" "Interfaces")
    (property "Tolerance" "")
    (property "Val" "0R")
    (property "ki_description" "0R resistor in 0402 package with unspecified tolerance")
    (attr smd)
    (fp_text reference "R140" (at -3.515 -0.34 -90) (layer "F.SilkS")
        (effects (font (size 0.7 0.7) (thickness 0.15)) (justify left bottom))
    )
    (fp_text value "R_0R_0402" (at 0 1.4 -90) (layer "F.Fab") hide
        (effects (font (size 0.7 0.7) (thickness 0.15)) (justify left bottom))
    )
    (fp_text user "Author: Antmicro" (at -0.95 4.169 -90) (layer "F.Fab") hide
        (effects (font (size 0.7 0.7) (thickness 0.15)) (justify left bottom))
    )
    (fp_text user "${REFERENCE}" (at -0.95 3.168 -90) (layer "F.Fab") hide
        (effects (font (size 0.7 0.7) (thickness 0.15)) (justify left bottom))
    )
    (fp_text user "License: Apache-2.0" (at -0.95 5.169 -90) (layer "F.Fab") hide
        (effects (font (size 0.7 0.7) (thickness 0.15)) (justify left bottom))
    )
    (fp_rect (start -0.93 -0.47) (end 0.93 0.47)
      (stroke (width 0.05) (type solid)) (fill none) (layer "F.CrtYd"))
    (fp_rect (start -0.5 -0.25) (end 0.5 0.25)
      (stroke (width 0.15) (type solid)) (fill none) (layer "F.Fab"))
    (pad "1" smd roundrect (at -0.485 0 270) (size 0.59 0.64) (layers "F.Cu" "F.Paste" "F.Mask") (roundrect_rratio 0.25)
      (net 55 "TMDS_CLK_P") (pintype "passive"))
    (pad "2" smd roundrect (at 0.485 0 270) (size 0.59 0.64) (layers "F.Cu" "F.Paste" "F.Mask") (roundrect_rratio 0.25)
      (net 42 "C_TMDS_CLK_P") (pintype "passive"))
  )
	(footprint "data-center-rdimm-ddr4-tester-footprints:R_0402_1005Metric" (layer "F.Cu")
    (at 210.14 115.35 -90)
    (descr "Resistor SMD 0402")
    (tags "resistor SMD 0402")
    (property "Author" "Antmicro")
    (property "Current" "1A")
    (property "License" "Apache-2.0")
    (property "MPN" "ERJ2GE0R00X")
    (property "Manufacturer" "Panasonic")
    (property "Sheetfile" "interfaces.kicad_sch")
    (property "Sheetname" "Interfaces")
    (property "Tolerance" "")
    (property "Val" "0R")
    (property "ki_description" "0R resistor in 0402 package with unspecified tolerance")
    (attr smd)
    (fp_text reference "R141" (at -3.105 -0.35 -90) (layer "F.SilkS")
        (effects (font (size 0.7 0.7) (thickness 0.15)) (justify left bottom))
    )
    (fp_text value "R_0R_0402" (at 0 1.4 -90) (layer "F.Fab") hide
        (effects (font (size 0.7 0.7) (thickness 0.15)) (justify left bottom))
    )
    (fp_text user "Author: Antmicro" (at -0.95 4.169 -90) (layer "F.Fab") hide
        (effects (font (size 0.7 0.7) (thickness 0.15)) (justify left bottom))
    )
    (fp_text user "License: Apache-2.0" (at -0.95 5.169 -90) (layer "F.Fab") hide
        (effects (font (size 0.7 0.7) (thickness 0.15)) (justify left bottom))
    )
    (fp_text user "${REFERENCE}" (at -0.95 3.168 -90) (layer "F.Fab") hide
        (effects (font (size 0.7 0.7) (thickness 0.15)) (justify left bottom))
    )
    (fp_rect (start -0.93 -0.47) (end 0.93 0.47)
      (stroke (width 0.05) (type solid)) (fill none) (layer "F.CrtYd"))
    (fp_rect (start -0.5 -0.25) (end 0.5 0.25)
      (stroke (width 0.15) (type solid)) (fill none) (layer "F.Fab"))
    (pad "1" smd roundrect (at -0.485 0 270) (size 0.59 0.64) (layers "F.Cu" "F.Paste" "F.Mask") (roundrect_rratio 0.25)
      (net 58 "TMDS_D0_N") (pintype "passive"))
    (pad "2" smd roundrect (at 0.485 0 270) (size 0.59 0.64) (layers "F.Cu" "F.Paste" "F.Mask") (roundrect_rratio 0.25)
      (net 44 "C_TMDS_D0_N") (pintype "passive"))
  )
)
